# T6G (Grand Teton) — schematic netlist excerpt (pin names and nets, part order shuffled) for the footprints in the layout excerpt that follows; sources: Cadence DE-HDL packaged netlist, KiCad conversion of 04192023_DAF0TMB3IC0_F0TG_MB_C_brd_V02_OCP.brd

R1701  Q_RES  10 1% CHIP  pkg 0402LF  page 102 : A = I3C_SPD_DDRAF_CPU1_SDA ; B = I3C_SPD_DDRE_CPU1_SDA
R1030  Q_RES  4.7K 5% EMPTY  pkg 0201LF  page 287 : A = P1V8_CPU0_RT_1D ; B = TEST0_RT_CPU0_P1
C6665  Q_CAP_DIFFBUS  DIFF BUS_0.22UF 6.3V 20% X6S  pkg C0201  page 330 : \1\ = P5E_CPU1_P1_TX_BUF_C_DP<2> ; \2\ = P5E_CPU1_P1_TX_BUF_DP<2>
R1432  Q_RES  1K 1% CHIP  pkg 0201LF  page 185 : A = P1V8_CPU0_RT_1D ; B = SMB_RT_CPU0_P2_ROM_MUX_1D_SCL

(kicad_pcb
	(version 20260206)
	(generator "pcbnew")
	(generator_version "10.0")
	(general
		(thickness 1.6)
		(legacy_teardrops no)
	)
	(paper "A4")
	(title_block
		(title "04192023_DAF0TMB3IC0_F0TG_MB_C_brd_V02_OCP.brd")
		(comment 1 "Grand Teton / footprints 6670-6673 of 8354")
	)
	(layers
		(0 "F.Cu" signal "TOP")
		(4 "In1.Cu" signal "GND")
		(6 "In2.Cu" signal "IN1")
		(8 "In3.Cu" signal "GND1")
		(10 "In4.Cu" signal "IN2")
		(12 "In5.Cu" signal "GND2")
		(14 "In6.Cu" signal "IN3")
		(16 "In7.Cu" signal "GND3")
		(18 "In8.Cu" signal "VCC")
		(20 "In9.Cu" signal "VCC1")
		(22 "In10.Cu" signal "GND4")
		(24 "In11.Cu" signal "IN4")
		(26 "In12.Cu" signal "GND5")
		(28 "In13.Cu" signal "IN5")
		(30 "In14.Cu" signal "GND6")
		(32 "In15.Cu" signal "IN6")
		(34 "In16.Cu" signal "GND7")
		(2 "B.Cu" signal "BOTTOM")
		(9 "F.Adhes" user "F.Adhesive")
		(11 "B.Adhes" user "B.Adhesive")
		(13 "F.Paste" user "Package Geometry/Pastemask Top")
		(15 "B.Paste" user "Package Geometry/Pastemask Bottom")
		(5 "F.SilkS" user "Ref Des/Silkscreen Top")
		(7 "B.SilkS" user "Ref Des/Silkscreen Bottom")
		(1 "F.Mask" user "Board Geometry/Soldermask Top")
		(3 "B.Mask" user "Board Geometry/Soldermask Bottom")
		(17 "Dwgs.User" user "User.Drawings")
		(19 "Cmts.User" user "User.Comments")
		(21 "Eco1.User" user "User.Eco1")
		(23 "Eco2.User" user "User.Eco2")
		(25 "Edge.Cuts" user "Board Geometry/Outline")
		(27 "Margin" user)
		(31 "F.CrtYd" user "Package Geometry/Place Bound Top")
		(29 "B.CrtYd" user "Package Geometry/Place Bound Bottom")
		(35 "F.Fab" user "Ref Des/Assembly Top")
		(33 "B.Fab" user "Ref Des/Assembly Bottom")
	)
	(footprint ""
		(layer "B.Cu")
		(at 424.664124 -428.118524 90)
		(property "Reference" "R1432"
			(at 0 0 90)
			(layer "B.SilkS")
			(hide yes)
			(effects
				(font
					(size 1.27 1.27)
				)
				(justify mirror)
			)
		)
		(property "Value" ""
			(at 0 0 90)
			(layer "B.Fab")
			(effects
				(font
					(size 1.27 1.27)
				)
				(justify mirror)
			)
		)
		(duplicate_pad_numbers_are_jumpers no)
		(fp_line
			(start 0.32512 -0.175006)
			(end -0.32512 -0.175006)
			(stroke
				(width 0.1)
				(type default)
			)
			(layer "B.Fab")
		)
		(fp_line
			(start -0.32512 -0.175006)
			(end -0.32512 0.175006)
			(stroke
				(width 0.1)
				(type default)
			)
			(layer "B.Fab")
		)
		(fp_line
			(start 0.32512 0.175006)
			(end 0.32512 -0.175006)
			(stroke
				(width 0.1)
				(type default)
			)
			(layer "B.Fab")
		)
		(fp_line
			(start -0.32512 0.175006)
			(end 0.32512 0.175006)
			(stroke
				(width 0.1)
				(type default)
			)
			(layer "B.Fab")
		)
		(pad "1" smd rect
			(at 0.2667 0 270)
			(size 0.3048 0.381)
			(layers "B.Cu" "B.Mask" "B.Paste")
			(net "P1V8_CPU0_RT_1D")
		)
		(pad "2" smd rect
			(at -0.2667 0 90)
			(size 0.3048 0.381)
			(layers "B.Cu" "B.Mask" "B.Paste")
			(net "SMB_RT_CPU0_P2_ROM_MUX_1D_SCL")
		)
	)
	(footprint ""
		(layer "B.Cu")
		(at 330.523342 -393.96416 180)
		(property "Reference" "R1030"
			(at 0 0 0)
			(layer "B.SilkS")
			(hide yes)
			(effects
				(font
					(size 1.27 1.27)
				)
				(justify mirror)
			)
		)
		(property "Value" ""
			(at 0 0 0)
			(layer "B.Fab")
			(effects
				(font
					(size 1.27 1.27)
				)
				(justify mirror)
			)
		)
		(duplicate_pad_numbers_are_jumpers no)
		(fp_line
			(start 0.32512 0.175006)
			(end 0.32512 -0.175006)
			(stroke
				(width 0.1)
				(type default)
			)
			(layer "B.Fab")
		)
		(fp_line
			(start 0.32512 -0.175006)
			(end -0.32512 -0.175006)
			(stroke
				(width 0.1)
				(type default)
			)
			(layer "B.Fab")
		)
		(fp_line
			(start -0.32512 0.175006)
			(end 0.32512 0.175006)
			(stroke
				(width 0.1)
				(type default)
			)
			(layer "B.Fab")
		)
		(fp_line
			(start -0.32512 -0.175006)
			(end -0.32512 0.175006)
			(stroke
				(width 0.1)
				(type default)
			)
			(layer "B.Fab")
		)
		(pad "1" smd rect
			(at 0.2667 0)
			(size 0.3048 0.381)
			(layers "B.Cu" "B.Mask" "B.Paste")
			(net "P1V8_CPU0_RT_1D")
		)
		(pad "2" smd rect
			(at -0.2667 0 180)
			(size 0.3048 0.381)
			(layers "B.Cu" "B.Mask" "B.Paste")
			(net "TEST0_RT_CPU0_P1")
		)
	)
	(footprint ""
		(layer "B.Cu")
		(at 28.46324 -195.926964 180)
		(property "Reference" "R1701"
			(at 0 0 0)
			(layer "B.SilkS")
			(hide yes)
			(effects
				(font
					(size 1.27 1.27)
				)
				(justify mirror)
			)
		)
		(property "Value" ""
			(at 0 0 0)
			(layer "B.Fab")
			(effects
				(font
					(size 1.27 1.27)
				)
				(justify mirror)
			)
		)
		(duplicate_pad_numbers_are_jumpers no)
		(fp_line
			(start 0.7874 0.4064)
			(end 0.7874 -0.4064)
			(stroke
				(width 0.1524)
				(type default)
			)
			(layer "B.SilkS")
		)
		(fp_line
			(start 0.7874 -0.4064)
			(end -0.7874 -0.4064)
			(stroke
				(width 0.1524)
				(type default)
			)
			(layer "B.SilkS")
		)
		(fp_line
			(start -0.7874 0.4064)
			(end 0.7874 0.4064)
			(stroke
				(width 0.1524)
				(type default)
			)
			(layer "B.SilkS")
		)
		(fp_line
			(start -0.7874 -0.4064)
			(end -0.7874 0.4064)
			(stroke
				(width 0.1524)
				(type default)
			)
			(layer "B.SilkS")
		)
		(fp_line
			(start 0.67945 0.3048)
			(end 0.67945 -0.305054)
			(stroke
				(width 0.1)
				(type default)
			)
			(layer "B.Fab")
		)
		(fp_line
			(start 0.67945 -0.305054)
			(end 0.12065 -0.305054)
			(stroke
				(width 0.1)
				(type default)
			)
			(layer "B.Fab")
		)
		(fp_line
			(start 0.12065 0.3048)
			(end 0.67945 0.3048)
			(stroke
				(width 0.1)
				(type default)
			)
			(layer "B.Fab")
		)
		(fp_line
			(start 0.12065 0.2794)
			(end 0.12065 0.3048)
			(stroke
				(width 0.1)
				(type default)
			)
			(layer "B.Fab")
		)
		(fp_line
			(start 0.12065 -0.2794)
			(end -0.12065 -0.2794)
			(stroke
				(width 0.1)
				(type default)
			)
			(layer "B.Fab")
		)
		(fp_line
			(start 0.12065 -0.305054)
			(end 0.12065 -0.2794)
			(stroke
				(width 0.1)
				(type default)
			)
			(layer "B.Fab")
		)
		(fp_line
			(start -0.120396 0.3048)
			(end -0.120396 0.2794)
			(stroke
				(width 0.1)
				(type default)
			)
			(layer "B.Fab")
		)
		(fp_line
			(start -0.120396 0.2794)
			(end 0.12065 0.2794)
			(stroke
				(width 0.1)
				(type default)
			)
			(layer "B.Fab")
		)
		(fp_line
			(start -0.12065 -0.2794)
			(end -0.12065 -0.3048)
			(stroke
				(width 0.1)
				(type default)
			)
			(layer "B.Fab")
		)
		(fp_line
			(start -0.12065 -0.3048)
			(end -0.67945 -0.3048)
			(stroke
				(width 0.1)
				(type default)
			)
			(layer "B.Fab")
		)
		(fp_line
			(start -0.67945 0.3048)
			(end -0.120396 0.3048)
			(stroke
				(width 0.1)
				(type default)
			)
			(layer "B.Fab")
		)
		(fp_line
			(start -0.67945 -0.3048)
			(end -0.67945 0.3048)
			(stroke
				(width 0.1)
				(type default)
			)
			(layer "B.Fab")
		)
		(pad "1" smd circle
			(at 0.40005 0)
			(size 0 0)
			(layers "B.Cu" "B.Mask" "B.Paste")
			(net "I3C_SPD_DDRAF_CPU1_SDA")
		)
		(pad "2" smd circle
			(at -0.40005 0)
			(size 0 0)
			(layers "B.Cu" "B.Mask" "B.Paste")
			(net "I3C_SPD_DDRE_CPU1_SDA")
		)
	)
	(footprint ""
		(layer "B.Cu")
		(at 56.341264 -408.517344 90)
		(property "Reference" "C6665"
			(at 0 0 90)
			(layer "B.SilkS")
			(hide yes)
			(effects
				(font
					(size 1.27 1.27)
				)
				(justify mirror)
			)
		)
		(property "Value" ""
			(at 0 0 90)
			(layer "B.Fab")
			(effects
				(font
					(size 1.27 1.27)
				)
				(justify mirror)
			)
		)
		(duplicate_pad_numbers_are_jumpers no)
		(fp_line
			(start 0.299974 -0.150114)
			(end -0.299974 -0.150114)
			(stroke
				(width 0.1)
				(type default)
			)
			(layer "B.Fab")
		)
		(fp_line
			(start -0.299974 -0.150114)
			(end -0.299974 0.150114)
			(stroke
				(width 0.1)
				(type default)
			)
			(layer "B.Fab")
		)
		(fp_line
			(start 0.299974 0.150114)
			(end 0.299974 -0.150114)
			(stroke
				(width 0.1)
				(type default)
			)
			(layer "B.Fab")
		)
		(fp_line
			(start -0.299974 0.150114)
			(end 0.299974 0.150114)
			(stroke
				(width 0.1)
				(type default)
			)
			(layer "B.Fab")
		)
		(pad "1" smd rect
			(at 0.2667 0 270)
			(size 0.3048 0.381)
			(layers "B.Cu" "B.Mask" "B.Paste")
			(net "P5E_CPU1_P1_TX_BUF_C_DP<2>")
		)
		(pad "2" smd rect
			(at -0.2667 0 270)
			(size 0.3048 0.381)
			(layers "B.Cu" "B.Mask" "B.Paste")
			(net "P5E_CPU1_P1_TX_BUF_DP<2>")
		)
	)
)
